(kicad_pcb
	(version 20260206)
	(generator "pcbnew")
	(generator_version "10.0")
	(general
		(thickness 1.6)
		(legacy_teardrops no)
	)
	(paper "A4")
	(title_block
		(title "pdpb — Lightning_PDPB_BRD.brd")
		(comment 1 "Lightning (Wiwynn / Facebook NVMe JBOF) / footprints 1001-1006 of 1140")
	)
	(layers
		(0 "F.Cu" signal "TOP")
		(4 "In1.Cu" signal "L2GND")
		(6 "In2.Cu" signal "L3")
		(8 "In3.Cu" signal "L4VCC")
		(10 "In4.Cu" signal "L5VCC")
		(12 "In5.Cu" signal "L6")
		(14 "In6.Cu" signal "L7GND")
		(2 "B.Cu" signal "BOTTOM")
		(9 "F.Adhes" user "F.Adhesive")
		(11 "B.Adhes" user "B.Adhesive")
		(13 "F.Paste" user "Package Geometry/Pastemask Top")
		(15 "B.Paste" user "Package Geometry/Pastemask Bottom")
		(5 "F.SilkS" user "Ref Des/Silkscreen Top")
		(7 "B.SilkS" user "Ref Des/Silkscreen Bottom")
		(1 "F.Mask" user "Board Geometry/Soldermask Top")
		(3 "B.Mask" user "Board Geometry/Soldermask Bottom")
		(17 "Dwgs.User" user "User.Drawings")
		(19 "Cmts.User" user "User.Comments")
		(21 "Eco1.User" user "User.Eco1")
		(23 "Eco2.User" user "User.Eco2")
		(25 "Edge.Cuts" user "Board Geometry/Outline")
		(27 "Margin" user)
		(31 "F.CrtYd" user "Package Geometry/Place Bound Top")
		(29 "B.CrtYd" user "Package Geometry/Place Bound Bottom")
		(35 "F.Fab" user "Ref Des/Assembly Top")
		(33 "B.Fab" user "Ref Des/Assembly Bottom")
	)
	(footprint ""
		(layer "F.Cu")
		(at 87.757 -317.246 -90)
		(property "Reference" "C9371"
			(at 0 0 270)
			(layer "F.SilkS")
			(hide yes)
			(effects
				(font
					(size 1.27 1.27)
				)
			)
		)
		(property "Value" "SC1KP50V2KX-1GP"
			(at 1.1811 -2.7051 270)
			(unlocked yes)
			(layer "F.Fab")
			(hide yes)
			(effects
				(font
					(size 1.016 1.016)
					(thickness 0.1524)
				)
			)
		)
		(property "Device Type" "C402H22"
			(at 1.1811 -4.2291 270)
			(unlocked yes)
			(layer "F.Fab")
			(hide yes)
			(effects
				(font
					(size 1.016 1.016)
					(thickness 0.1524)
				)
			)
		)
		(duplicate_pad_numbers_are_jumpers no)
		(fp_rect
			(start -0.4318 0.9525)
			(end 0.4318 -0.9525)
			(stroke
				(width 0)
				(type default)
			)
			(fill no)
			(layer "F.CrtYd")
		)
		(fp_rect
			(start -0.4318 0.9525)
			(end 0.4318 -0.9525)
			(stroke
				(width 0)
				(type default)
			)
			(fill no)
			(layer "F.Fab")
		)
		(pad "1" smd custom
			(at 0 -0.4445 270)
			(size 0.1524 0.1524)
			(layers "F.Cu" "F.Mask" "F.Paste")
			(net "SSD11_CLK0_OE_R_N")
			(options
				(clearance outline)
				(anchor circle)
			)
			(primitives
				(gr_poly
					(pts
						(arc
							(start 0.3048 -0.2032)
							(mid 0.275042 -0.275042)
							(end 0.2032 -0.3048)
						)
						(arc
							(start -0.2032 -0.3048)
							(mid -0.275042 -0.275042)
							(end -0.3048 -0.2032)
						)
						(arc
							(start -0.3048 0.2032)
							(mid -0.275042 0.275042)
							(end -0.2032 0.3048)
						)
						(arc
							(start 0.2032 0.3048)
							(mid 0.275042 0.275042)
							(end 0.3048 0.2032)
						)
					)
					(width 0)
					(fill yes)
				)
			)
		)
		(pad "2" smd custom
			(at 0 0.4445 270)
			(size 0.1524 0.1524)
			(layers "F.Cu" "F.Mask" "F.Paste")
			(net "GND")
			(options
				(clearance outline)
				(anchor circle)
			)
			(primitives
				(gr_poly
					(pts
						(arc
							(start 0.3048 -0.2032)
							(mid 0.275042 -0.275042)
							(end 0.2032 -0.3048)
						)
						(arc
							(start -0.2032 -0.3048)
							(mid -0.275042 -0.275042)
							(end -0.3048 -0.2032)
						)
						(arc
							(start -0.3048 0.2032)
							(mid -0.275042 0.275042)
							(end -0.2032 0.3048)
						)
						(arc
							(start 0.2032 0.3048)
							(mid 0.275042 0.275042)
							(end 0.3048 0.2032)
						)
					)
					(width 0)
					(fill yes)
				)
			)
		)
	)
	(footprint ""
		(layer "F.Cu")
		(at 36.2712 -95.3262 -90)
		(property "Reference" "R9838"
			(at 0 0 270)
			(layer "F.SilkS")
			(hide yes)
			(effects
				(font
					(size 1.27 1.27)
				)
			)
		)
		(property "Value" "2K2R5F-GP"
			(at 0 -8.9535 270)
			(unlocked yes)
			(layer "F.Fab")
			(hide yes)
			(effects
				(font
					(size 1.27 1.016)
					(thickness 0.1524)
				)
			)
		)
		(property "Device Type" "R805H24"
			(at 0 -10.6299 270)
			(unlocked yes)
			(layer "F.Fab")
			(hide yes)
			(effects
				(font
					(size 1.27 1.016)
					(thickness 0.1524)
				)
			)
		)
		(duplicate_pad_numbers_are_jumpers no)
		(fp_line
			(start -0.889 1.7018)
			(end 0.889 1.7018)
			(stroke
				(width 0.1524)
				(type default)
			)
			(layer "F.SilkS")
		)
		(fp_line
			(start 0.889 1.7018)
			(end 0.889 -0.508)
			(stroke
				(width 0.1524)
				(type default)
			)
			(layer "F.SilkS")
		)
		(fp_line
			(start -0.889 0.0762)
			(end -0.889 1.7018)
			(stroke
				(width 0.1524)
				(type default)
			)
			(layer "F.SilkS")
		)
		(fp_line
			(start -0.889 -1.7018)
			(end -0.889 0.2794)
			(stroke
				(width 0.1524)
				(type default)
			)
			(layer "F.SilkS")
		)
		(fp_line
			(start 0.889 -1.7018)
			(end 0.889 -0.381)
			(stroke
				(width 0.1524)
				(type default)
			)
			(layer "F.SilkS")
		)
		(fp_line
			(start 0.889 -1.7018)
			(end -0.889 -1.7018)
			(stroke
				(width 0.1524)
				(type default)
			)
			(layer "F.SilkS")
		)
		(fp_poly
			(pts
				(xy 0.9652 -1.778) (xy 0.9652 1.778) (xy -0.9652 1.778) (xy -0.9652 -1.778)
			)
			(stroke
				(width 0)
				(type default)
			)
			(fill no)
			(layer "F.CrtYd")
		)
		(fp_rect
			(start -0.9652 1.778)
			(end 0.9652 -1.778)
			(stroke
				(width 0)
				(type default)
			)
			(fill no)
			(layer "F.Fab")
		)
		(pad "1" smd rect
			(at 0 -0.9652 270)
			(size 1.397 1.143)
			(layers "F.Cu" "F.Mask" "F.Paste")
			(net "P12V_SSD9")
		)
		(pad "2" smd rect
			(at 0 0.9652 270)
			(size 1.397 1.143)
			(layers "F.Cu" "F.Mask" "F.Paste")
			(net "P12V_MOST9_GATE_D")
		)
	)
	(footprint ""
		(layer "F.Cu")
		(at 70.000114 -71.000112)
		(property "Reference" "H10"
			(at 0 0 0)
			(layer "F.SilkS")
			(hide yes)
			(effects
				(font
					(size 1.27 1.27)
				)
			)
		)
		(property "Value" "GEN276X162R197X296-6-F-A-GP"
			(at -6.7183 4.1402 0)
			(unlocked yes)
			(layer "F.Fab")
			(hide yes)
			(effects
				(font
					(size 1.016 1.016)
					(thickness 0.1524)
				)
			)
		)
		(property "Device Type" "GEN276X162R197X296-6-F-A"
			(at -6.7183 2.6162 0)
			(unlocked yes)
			(layer "F.Fab")
			(hide yes)
			(effects
				(font
					(size 1.016 1.016)
					(thickness 0.1524)
				)
			)
		)
		(duplicate_pad_numbers_are_jumpers no)
		(fp_poly
			(pts
				(arc
					(start 2.723642 4.777232)
					(mid -0.000169 6.508462)
					(end -2.723896 4.776978)
				)
				(arc
					(start -2.723896 4.776978)
					(mid 0.000173 -5.499012)
					(end 2.723642 4.777232)
				)
			)
			(stroke
				(width 0)
				(type default)
			)
			(fill no)
			(layer "B.CrtYd")
		)
		(fp_poly
			(pts
				(arc
					(start 2.723642 4.777232)
					(mid -0.000169 6.508462)
					(end -2.723896 4.776978)
				)
				(arc
					(start -2.723896 4.776978)
					(mid 0.000173 -5.499012)
					(end 2.723642 4.777232)
				)
			)
			(stroke
				(width 0)
				(type default)
			)
			(fill no)
			(layer "F.CrtYd")
		)
		(fp_poly
			(pts
				(arc
					(start 2.723642 4.777232)
					(mid -0.000169 6.508462)
					(end -2.723896 4.776978)
				)
				(arc
					(start -2.723896 4.776978)
					(mid 0.000173 -5.499012)
					(end 2.723642 4.777232)
				)
			)
			(stroke
				(width 0)
				(type default)
			)
			(fill no)
			(layer "B.Fab")
		)
		(fp_poly
			(pts
				(arc
					(start 2.723642 4.777232)
					(mid -0.000169 6.508462)
					(end -2.723896 4.776978)
				)
				(arc
					(start -2.723896 4.776978)
					(mid 0.000173 -5.499012)
					(end 2.723642 4.777232)
				)
			)
			(stroke
				(width 0)
				(type default)
			)
			(fill no)
			(layer "F.Fab")
		)
		(pad "" np_thru_hole circle
			(at 0 0)
			(size 0.254 0.254)
			(drill 0.0254)
			(layers "*.Cu" "*.Mask")
			(clearance 3.135376)
			(thermal_gap 3.135376)
		)
		(pad "1" thru_hole circle
			(at 2.549906 0)
			(size 0.8636 0.8636)
			(drill 0.508)
			(layers "*.Cu" "*.Mask")
			(remove_unused_layers no)
			(net "GND")
			(clearance 0.8255)
			(thermal_gap 0.8255)
		)
		(pad "2" thru_hole circle
			(at 2.210054 -1.27)
			(size 0.8636 0.8636)
			(drill 0.508)
			(layers "*.Cu" "*.Mask")
			(remove_unused_layers no)
			(net "GND")
			(clearance 0.8255)
			(thermal_gap 0.8255)
		)
		(pad "3" thru_hole circle
			(at 1.27 -2.210054)
			(size 0.8636 0.8636)
			(drill 0.508)
			(layers "*.Cu" "*.Mask")
			(remove_unused_layers no)
			(net "GND")
			(clearance 0.8255)
			(thermal_gap 0.8255)
		)
		(pad "4" thru_hole circle
			(at -1.279906 -2.210054)
			(size 0.8636 0.8636)
			(drill 0.508)
			(layers "*.Cu" "*.Mask")
			(remove_unused_layers no)
			(net "GND")
			(clearance 0.8255)
			(thermal_gap 0.8255)
		)
		(pad "5" thru_hole circle
			(at -2.210054 -1.27)
			(size 0.8636 0.8636)
			(drill 0.508)
			(layers "*.Cu" "*.Mask")
			(remove_unused_layers no)
			(net "GND")
			(clearance 0.8255)
			(thermal_gap 0.8255)
		)
		(pad "6" thru_hole circle
			(at -2.549906 0)
			(size 0.8636 0.8636)
			(drill 0.508)
			(layers "*.Cu" "*.Mask")
			(remove_unused_layers no)
			(net "GND")
			(clearance 0.8255)
			(thermal_gap 0.8255)
		)
		(zone
			(layers "F.Cu" "B.Cu" "In1.Cu" "In2.Cu" "In3.Cu" "In4.Cu" "In5.Cu" "In6.Cu")
			(hatch none 0.5)
			(connect_pads
				(clearance 0)
			)
			(min_thickness 0.25)
			(keepout
				(tracks allowed)
				(vias not_allowed)
				(pads allowed)
				(copperpour not_allowed)
				(footprints allowed)
			)
			(placement
				(enabled no)
				(sheetname "")
			)
			(fill
				(thermal_gap 0.5)
				(thermal_bridge_width 0.5)
				(island_removal_mode 0)
			)
			(polygon
				(pts
					(arc
						(start 74.318114 -71.00316)
						(mid 65.682114 -71.00316)
						(end 74.318114 -71.00316)
					)
				)
			)
		)
		(zone
			(layers "F.Cu" "B.Cu" "In1.Cu" "In2.Cu" "In3.Cu" "In4.Cu" "In5.Cu" "In6.Cu")
			(hatch none 0.5)
			(connect_pads
				(clearance 0)
			)
			(min_thickness 0.25)
			(keepout
				(tracks not_allowed)
				(vias allowed)
				(pads allowed)
				(copperpour not_allowed)
				(footprints allowed)
			)
			(placement
				(enabled no)
				(sheetname "")
			)
			(fill
				(thermal_gap 0.5)
				(thermal_bridge_width 0.5)
				(island_removal_mode 0)
			)
			(polygon
				(pts
					(arc
						(start 72.339454 -69.390768)
						(mid 70.000194 -64.491665)
						(end 67.66052 -69.390768)
					)
					(arc
						(start 67.66052 -69.390768)
						(mid 67.906487 -69.831134)
						(end 67.991736 -70.328282)
					)
					(arc
						(start 67.991736 -71.000112)
						(mid 70.000114 -73.00849)
						(end 72.008238 -71.000112)
					)
					(arc
						(start 72.008238 -70.328282)
						(mid 72.093473 -69.831128)
						(end 72.339454 -69.390768)
					)
				)
			)
		)
	)
	(footprint ""
		(layer "F.Cu")
		(at 45.9359 -7.4549)
		(property "Reference" "R9872"
			(at 0 0 0)
			(layer "F.SilkS")
			(hide yes)
			(effects
				(font
					(size 1.27 1.27)
				)
			)
		)
		(property "Value" "47KR2J-2-GP"
			(at 0.064008 -3.993896 0)
			(unlocked yes)
			(layer "F.Fab")
			(hide yes)
			(effects
				(font
					(size 1.016 1.016)
					(thickness 0.1524)
				)
			)
		)
		(property "Device Type" "R402H16"
			(at 0.064008 -5.517896 0)
			(unlocked yes)
			(layer "F.Fab")
			(hide yes)
			(effects
				(font
					(size 1.016 1.016)
					(thickness 0.1524)
				)
			)
		)
		(duplicate_pad_numbers_are_jumpers no)
		(fp_line
			(start -0.508 -0.9398)
			(end -0.508 0.9398)
			(stroke
				(width 0.1524)
				(type default)
			)
			(layer "F.SilkS")
		)
		(fp_line
			(start 0.508 -0.9398)
			(end -0.508 -0.9398)
			(stroke
				(width 0.1524)
				(type default)
			)
			(layer "F.SilkS")
		)
		(fp_rect
			(start -0.508 0.9398)
			(end 0.508 -0.9398)
			(stroke
				(width 0)
				(type default)
			)
			(fill no)
			(layer "F.CrtYd")
		)
		(fp_rect
			(start -0.508 0.9398)
			(end 0.508 -0.9398)
			(stroke
				(width 0)
				(type default)
			)
			(fill no)
			(layer "F.Fab")
		)
		(pad "1" smd custom
			(at 0 -0.4445)
			(size 0.1397 0.1397)
			(layers "F.Cu" "F.Mask" "F.Paste")
			(net "P12V")
			(options
				(clearance outline)
				(anchor circle)
			)
			(primitives
				(gr_poly
					(pts
						(arc
							(start -0.1778 -0.2794)
							(mid -0.249642 -0.249642)
							(end -0.2794 -0.1778)
						)
						(arc
							(start -0.2794 0.1778)
							(mid -0.249642 0.249642)
							(end -0.1778 0.2794)
						)
						(arc
							(start 0.1778 0.2794)
							(mid 0.249642 0.249642)
							(end 0.2794 0.1778)
						)
						(arc
							(start 0.2794 -0.1778)
							(mid 0.249642 -0.249642)
							(end 0.1778 -0.2794)
						)
					)
					(width 0)
					(fill yes)
				)
			)
		)
		(pad "2" smd custom
			(at 0 0.4445)
			(size 0.1397 0.1397)
			(layers "F.Cu" "F.Mask" "F.Paste")
			(net "P12V_MOST14_GATE")
			(options
				(clearance outline)
				(anchor circle)
			)
			(primitives
				(gr_poly
					(pts
						(arc
							(start -0.1778 -0.2794)
							(mid -0.249642 -0.249642)
							(end -0.2794 -0.1778)
						)
						(arc
							(start -0.2794 0.1778)
							(mid -0.249642 0.249642)
							(end -0.1778 0.2794)
						)
						(arc
							(start 0.1778 0.2794)
							(mid 0.249642 0.249642)
							(end 0.2794 0.1778)
						)
						(arc
							(start 0.2794 -0.1778)
							(mid 0.249642 -0.249642)
							(end 0.1778 -0.2794)
						)
					)
					(width 0)
					(fill yes)
				)
			)
		)
	)
	(footprint ""
		(layer "F.Cu")
		(at 217.043 -390.525 -90)
		(property "Reference" "R385"
			(at 0 0 270)
			(layer "F.SilkS")
			(hide yes)
			(effects
				(font
					(size 1.27 1.27)
				)
			)
		)
		(property "Value" "0R2J-2-GP"
			(at 0.064008 -3.993896 270)
			(unlocked yes)
			(layer "F.Fab")
			(hide yes)
			(effects
				(font
					(size 1.016 1.016)
					(thickness 0.1524)
				)
			)
		)
		(property "Device Type" "R402H16"
			(at 0.064008 -5.517896 270)
			(unlocked yes)
			(layer "F.Fab")
			(hide yes)
			(effects
				(font
					(size 1.016 1.016)
					(thickness 0.1524)
				)
			)
		)
		(duplicate_pad_numbers_are_jumpers no)
		(fp_line
			(start -0.508 -0.9398)
			(end -0.508 0.9398)
			(stroke
				(width 0.1524)
				(type default)
			)
			(layer "F.SilkS")
		)
		(fp_line
			(start 0.508 -0.9398)
			(end -0.508 -0.9398)
			(stroke
				(width 0.1524)
				(type default)
			)
			(layer "F.SilkS")
		)
		(fp_rect
			(start -0.508 0.9398)
			(end 0.508 -0.9398)
			(stroke
				(width 0)
				(type default)
			)
			(fill no)
			(layer "F.CrtYd")
		)
		(fp_rect
			(start -0.508 0.9398)
			(end 0.508 -0.9398)
			(stroke
				(width 0)
				(type default)
			)
			(fill no)
			(layer "F.Fab")
		)
		(pad "1" smd custom
			(at 0 -0.4445 270)
			(size 0.1397 0.1397)
			(layers "F.Cu" "F.Mask" "F.Paste")
			(net "SCL_DR1_R")
			(options
				(clearance outline)
				(anchor circle)
			)
			(primitives
				(gr_poly
					(pts
						(arc
							(start -0.1778 -0.2794)
							(mid -0.249642 -0.249642)
							(end -0.2794 -0.1778)
						)
						(arc
							(start -0.2794 0.1778)
							(mid -0.249642 0.249642)
							(end -0.1778 0.2794)
						)
						(arc
							(start 0.1778 0.2794)
							(mid 0.249642 0.249642)
							(end 0.2794 0.1778)
						)
						(arc
							(start 0.2794 -0.1778)
							(mid 0.249642 -0.249642)
							(end 0.1778 -0.2794)
						)
					)
					(width 0)
					(fill yes)
				)
			)
		)
		(pad "2" smd custom
			(at 0 0.4445 270)
			(size 0.1397 0.1397)
			(layers "F.Cu" "F.Mask" "F.Paste")
			(net "SCL_DR1")
			(options
				(clearance outline)
				(anchor circle)
			)
			(primitives
				(gr_poly
					(pts
						(arc
							(start -0.1778 -0.2794)
							(mid -0.249642 -0.249642)
							(end -0.2794 -0.1778)
						)
						(arc
							(start -0.2794 0.1778)
							(mid -0.249642 0.249642)
							(end -0.1778 0.2794)
						)
						(arc
							(start 0.1778 0.2794)
							(mid 0.249642 0.249642)
							(end 0.2794 0.1778)
						)
						(arc
							(start 0.2794 -0.1778)
							(mid 0.249642 -0.249642)
							(end 0.1778 -0.2794)
						)
					)
					(width 0)
					(fill yes)
				)
			)
		)
	)
	(footprint ""
		(layer "F.Cu")
		(at 39.116 -308.737)
		(property "Reference" "R9752"
			(at 0 0 0)
			(layer "F.SilkS")
			(hide yes)
			(effects
				(font
					(size 1.27 1.27)
				)
			)
		)
		(property "Value" "4K7R2J-2-GP"
			(at 0.064008 -3.993896 0)
			(unlocked yes)
			(layer "F.Fab")
			(hide yes)
			(effects
				(font
					(size 1.016 1.016)
					(thickness 0.1524)
				)
			)
		)
		(property "Device Type" "R402H16"
			(at 0.064008 -5.517896 0)
			(unlocked yes)
			(layer "F.Fab")
			(hide yes)
			(effects
				(font
					(size 1.016 1.016)
					(thickness 0.1524)
				)
			)
		)
		(duplicate_pad_numbers_are_jumpers no)
		(fp_line
			(start -0.508 -0.9398)
			(end -0.508 0.9398)
			(stroke
				(width 0.1524)
				(type default)
			)
			(layer "F.SilkS")
		)
		(fp_line
			(start 0.508 -0.9398)
			(end -0.508 -0.9398)
			(stroke
				(width 0.1524)
				(type default)
			)
			(layer "F.SilkS")
		)
		(fp_rect
			(start -0.508 0.9398)
			(end 0.508 -0.9398)
			(stroke
				(width 0)
				(type default)
			)
			(fill no)
			(layer "F.CrtYd")
		)
		(fp_rect
			(start -0.508 0.9398)
			(end 0.508 -0.9398)
			(stroke
				(width 0)
				(type default)
			)
			(fill no)
			(layer "F.Fab")
		)
		(pad "1" smd custom
			(at 0 -0.4445)
			(size 0.1397 0.1397)
			(layers "F.Cu" "F.Mask" "F.Paste")
			(net "P3V3")
			(options
				(clearance outline)
				(anchor circle)
			)
			(primitives
				(gr_poly
					(pts
						(arc
							(start -0.1778 -0.2794)
							(mid -0.249642 -0.249642)
							(end -0.2794 -0.1778)
						)
						(arc
							(start -0.2794 0.1778)
							(mid -0.249642 0.249642)
							(end -0.1778 0.2794)
						)
						(arc
							(start 0.1778 0.2794)
							(mid 0.249642 0.249642)
							(end 0.2794 0.1778)
						)
						(arc
							(start 0.2794 -0.1778)
							(mid 0.249642 -0.249642)
							(end 0.1778 -0.2794)
						)
					)
					(width 0)
					(fill yes)
				)
			)
		)
		(pad "2" smd custom
			(at 0 0.4445)
			(size 0.1397 0.1397)
			(layers "F.Cu" "F.Mask" "F.Paste")
			(net "SSD11_PWREN")
			(options
				(clearance outline)
				(anchor circle)
			)
			(primitives
				(gr_poly
					(pts
						(arc
							(start -0.1778 -0.2794)
							(mid -0.249642 -0.249642)
							(end -0.2794 -0.1778)
						)
						(arc
							(start -0.2794 0.1778)
							(mid -0.249642 0.249642)
							(end -0.1778 0.2794)
						)
						(arc
							(start 0.1778 0.2794)
							(mid 0.249642 0.249642)
							(end 0.2794 0.1778)
						)
						(arc
							(start 0.2794 -0.1778)
							(mid 0.249642 -0.249642)
							(end 0.1778 -0.2794)
						)
					)
					(width 0)
					(fill yes)
				)
			)
		)
	)
)
